(kicad_pcb
	(version 20260206)
	(generator "pcbnew")
	(generator_version "10.0")
	(general
		(thickness 1.6)
		(legacy_teardrops no)
	)
	(paper "A4")
	(title_block
		(title "fcb — Lightning_FCB_BRD.brd")
		(comment 1 "Lightning (Wiwynn / Facebook NVMe JBOF) / footprints 80-82 of 495")
	)
	(layers
		(0 "F.Cu" signal "TOP")
		(4 "In1.Cu" signal "L2GND")
		(6 "In2.Cu" signal "L3VCC")
		(2 "B.Cu" signal "BOTTOM")
		(9 "F.Adhes" user "F.Adhesive")
		(11 "B.Adhes" user "B.Adhesive")
		(13 "F.Paste" user "Package Geometry/Pastemask Top")
		(15 "B.Paste" user "Package Geometry/Pastemask Bottom")
		(5 "F.SilkS" user "Ref Des/Silkscreen Top")
		(7 "B.SilkS" user "Ref Des/Silkscreen Bottom")
		(1 "F.Mask" user "Board Geometry/Soldermask Top")
		(3 "B.Mask" user "Board Geometry/Soldermask Bottom")
		(17 "Dwgs.User" user "User.Drawings")
		(19 "Cmts.User" user "User.Comments")
		(21 "Eco1.User" user "User.Eco1")
		(23 "Eco2.User" user "User.Eco2")
		(25 "Edge.Cuts" user "Board Geometry/Outline")
		(27 "Margin" user)
		(31 "F.CrtYd" user "Package Geometry/Place Bound Top")
		(29 "B.CrtYd" user "Package Geometry/Place Bound Bottom")
		(35 "F.Fab" user "Ref Des/Assembly Top")
		(33 "B.Fab" user "Ref Des/Assembly Bottom")
	)
	(footprint ""
		(layer "F.Cu")
		(at 4.499864 -340.000082)
		(property "Reference" "H4"
			(at 0 0 0)
			(layer "F.SilkS")
			(hide yes)
			(effects
				(font
					(size 1.27 1.27)
				)
			)
		)
		(property "Value" "HOLE315R138"
			(at 0 -7.0612 0)
			(unlocked yes)
			(layer "F.Fab")
			(hide yes)
			(effects
				(font
					(size 1.016 1.016)
					(thickness 0.1524)
				)
			)
		)
		(property "Device Type" "HOLE315R138"
			(at 0 -8.5852 0)
			(unlocked yes)
			(layer "F.Fab")
			(hide yes)
			(effects
				(font
					(size 1.016 1.016)
					(thickness 0.1524)
				)
			)
		)
		(duplicate_pad_numbers_are_jumpers no)
		(fp_poly
			(pts
				(xy 0 4.3053) (xy -0.13462 4.30276) (xy -0.27051 4.29641) (xy -0.40513 4.28625) (xy -0.53975 4.27101)
				(xy -0.6731 4.25196) (xy -0.80645 4.2291) (xy -0.9398 4.20116) (xy -1.07061 4.17068) (xy -1.20142 4.13385)
				(xy -1.33096 4.09448) (xy -1.45796 4.0513) (xy -1.58496 4.00304) (xy -1.70942 3.95097) (xy -1.83261 3.89509)
				(xy -1.95453 3.83667) (xy -2.07391 3.77317) (xy -2.19202 3.70586) (xy -2.30632 3.63474) (xy -2.41935 3.56108)
				(xy -2.53111 3.48361) (xy -2.63906 3.40233) (xy -2.74447 3.31724) (xy -2.84734 3.22961) (xy -2.94767 3.13817)
				(xy -3.04419 3.04419) (xy -3.13817 2.94767) (xy -3.22961 2.84734) (xy -3.31724 2.74447) (xy -3.40233 2.63906)
				(xy -3.48361 2.53111) (xy -3.56108 2.41935) (xy -3.63474 2.30632) (xy -3.70586 2.19202) (xy -3.77317 2.07391)
				(xy -3.83667 1.95453) (xy -3.89509 1.83261) (xy -3.95097 1.70942) (xy -4.00304 1.58496) (xy -4.0513 1.45796)
				(xy -4.09448 1.33096) (xy -4.13385 1.20142) (xy -4.17068 1.07061) (xy -4.20116 0.9398) (xy -4.2291 0.80645)
				(xy -4.25196 0.6731) (xy -4.27101 0.53975) (xy -4.28625 0.40513) (xy -4.29641 0.27051) (xy -4.30276 0.13462)
				(xy -4.3053 0) (xy -4.30276 -0.13462) (xy -4.29641 -0.27051) (xy -4.28625 -0.40513) (xy -4.27101 -0.53975)
				(xy -4.25196 -0.6731) (xy -4.2291 -0.80645) (xy -4.20116 -0.9398) (xy -4.17068 -1.07061) (xy -4.13385 -1.20142)
				(xy -4.09448 -1.33096) (xy -4.0513 -1.45796) (xy -4.00304 -1.58496) (xy -3.95097 -1.70942) (xy -3.89509 -1.83261)
				(xy -3.83667 -1.95453) (xy -3.77317 -2.07391) (xy -3.70586 -2.19202) (xy -3.63474 -2.30632) (xy -3.56108 -2.41935)
				(xy -3.48361 -2.53111) (xy -3.40233 -2.63906) (xy -3.31724 -2.74447) (xy -3.22961 -2.84734) (xy -3.13817 -2.94767)
				(xy -3.04419 -3.04419) (xy -2.94767 -3.13817) (xy -2.84734 -3.22961) (xy -2.74447 -3.31724) (xy -2.63906 -3.40233)
				(xy -2.53111 -3.48361) (xy -2.41935 -3.56108) (xy -2.30632 -3.63474) (xy -2.19202 -3.70586) (xy -2.07391 -3.77317)
				(xy -1.95453 -3.83667) (xy -1.83261 -3.89509) (xy -1.70942 -3.95097) (xy -1.58496 -4.00304) (xy -1.45796 -4.0513)
				(xy -1.33096 -4.09448) (xy -1.20142 -4.13385) (xy -1.07061 -4.17068) (xy -0.9398 -4.20116) (xy -0.80645 -4.2291)
				(xy -0.6731 -4.25196) (xy -0.53975 -4.27101) (xy -0.40513 -4.28625) (xy -0.27051 -4.29641) (xy -0.13462 -4.30276)
				(xy 0 -4.3053) (xy 0.13462 -4.30276) (xy 0.27051 -4.29641) (xy 0.40513 -4.28625) (xy 0.53975 -4.27101)
				(xy 0.6731 -4.25196) (xy 0.80645 -4.2291) (xy 0.9398 -4.20116) (xy 1.07061 -4.17068) (xy 1.20142 -4.13385)
				(xy 1.33096 -4.09448) (xy 1.45796 -4.0513) (xy 1.58496 -4.00304) (xy 1.70942 -3.95097) (xy 1.83261 -3.89509)
				(xy 1.95453 -3.83667) (xy 2.07391 -3.77317) (xy 2.19202 -3.70586) (xy 2.30632 -3.63474) (xy 2.41935 -3.56108)
				(xy 2.53111 -3.48361) (xy 2.63906 -3.40233) (xy 2.74447 -3.31724) (xy 2.84734 -3.22961) (xy 2.94767 -3.13817)
				(xy 3.04419 -3.04419) (xy 3.13817 -2.94767) (xy 3.22961 -2.84734) (xy 3.31724 -2.74447) (xy 3.40233 -2.63906)
				(xy 3.48361 -2.53111) (xy 3.56108 -2.41935) (xy 3.63474 -2.30632) (xy 3.70586 -2.19202) (xy 3.77317 -2.07391)
				(xy 3.83667 -1.95453) (xy 3.89509 -1.83261) (xy 3.95097 -1.70942) (xy 4.00304 -1.58496) (xy 4.0513 -1.45796)
				(xy 4.09448 -1.33096) (xy 4.13385 -1.20142) (xy 4.17068 -1.07061) (xy 4.20116 -0.9398) (xy 4.2291 -0.80645)
				(xy 4.25196 -0.6731) (xy 4.27101 -0.53975) (xy 4.28625 -0.40513) (xy 4.29641 -0.27051) (xy 4.30276 -0.13462)
				(xy 4.3053 0) (xy 4.30276 0.13462) (xy 4.29641 0.27051) (xy 4.28625 0.40513) (xy 4.27101 0.53975)
				(xy 4.25196 0.6731) (xy 4.2291 0.80645) (xy 4.20116 0.9398) (xy 4.17068 1.07061) (xy 4.13385 1.20142)
				(xy 4.09448 1.33096) (xy 4.0513 1.45796) (xy 4.00304 1.58496) (xy 3.95097 1.70942) (xy 3.89509 1.83261)
				(xy 3.83667 1.95453) (xy 3.77317 2.07391) (xy 3.70586 2.19202) (xy 3.63474 2.30632) (xy 3.56108 2.41935)
				(xy 3.48361 2.53111) (xy 3.40233 2.63906) (xy 3.31724 2.74447) (xy 3.22961 2.84734) (xy 3.13817 2.94767)
				(xy 3.04419 3.04419) (xy 2.94767 3.13817) (xy 2.84734 3.22961) (xy 2.74447 3.31724) (xy 2.63906 3.40233)
				(xy 2.53111 3.48361) (xy 2.41935 3.56108) (xy 2.30632 3.63474) (xy 2.19202 3.70586) (xy 2.07391 3.77317)
				(xy 1.95453 3.83667) (xy 1.83261 3.89509) (xy 1.70942 3.95097) (xy 1.58496 4.00304) (xy 1.45796 4.0513)
				(xy 1.33096 4.09448) (xy 1.20142 4.13385) (xy 1.07061 4.17068) (xy 0.9398 4.20116) (xy 0.80645 4.2291)
				(xy 0.6731 4.25196) (xy 0.53975 4.27101) (xy 0.40513 4.28625) (xy 0.27051 4.29641) (xy 0.13462 4.30276)
			)
			(stroke
				(width 0)
				(type default)
			)
			(fill no)
			(layer "F.CrtYd")
		)
		(fp_poly
			(pts
				(xy 0 4.3053) (xy -0.13462 4.30276) (xy -0.27051 4.29641) (xy -0.40513 4.28625) (xy -0.53975 4.27101)
				(xy -0.6731 4.25196) (xy -0.80645 4.2291) (xy -0.9398 4.20116) (xy -1.07061 4.17068) (xy -1.20142 4.13385)
				(xy -1.33096 4.09448) (xy -1.45796 4.0513) (xy -1.58496 4.00304) (xy -1.70942 3.95097) (xy -1.83261 3.89509)
				(xy -1.95453 3.83667) (xy -2.07391 3.77317) (xy -2.19202 3.70586) (xy -2.30632 3.63474) (xy -2.41935 3.56108)
				(xy -2.53111 3.48361) (xy -2.63906 3.40233) (xy -2.74447 3.31724) (xy -2.84734 3.22961) (xy -2.94767 3.13817)
				(xy -3.04419 3.04419) (xy -3.13817 2.94767) (xy -3.22961 2.84734) (xy -3.31724 2.74447) (xy -3.40233 2.63906)
				(xy -3.48361 2.53111) (xy -3.56108 2.41935) (xy -3.63474 2.30632) (xy -3.70586 2.19202) (xy -3.77317 2.07391)
				(xy -3.83667 1.95453) (xy -3.89509 1.83261) (xy -3.95097 1.70942) (xy -4.00304 1.58496) (xy -4.0513 1.45796)
				(xy -4.09448 1.33096) (xy -4.13385 1.20142) (xy -4.17068 1.07061) (xy -4.20116 0.9398) (xy -4.2291 0.80645)
				(xy -4.25196 0.6731) (xy -4.27101 0.53975) (xy -4.28625 0.40513) (xy -4.29641 0.27051) (xy -4.30276 0.13462)
				(xy -4.3053 0) (xy -4.30276 -0.13462) (xy -4.29641 -0.27051) (xy -4.28625 -0.40513) (xy -4.27101 -0.53975)
				(xy -4.25196 -0.6731) (xy -4.2291 -0.80645) (xy -4.20116 -0.9398) (xy -4.17068 -1.07061) (xy -4.13385 -1.20142)
				(xy -4.09448 -1.33096) (xy -4.0513 -1.45796) (xy -4.00304 -1.58496) (xy -3.95097 -1.70942) (xy -3.89509 -1.83261)
				(xy -3.83667 -1.95453) (xy -3.77317 -2.07391) (xy -3.70586 -2.19202) (xy -3.63474 -2.30632) (xy -3.56108 -2.41935)
				(xy -3.48361 -2.53111) (xy -3.40233 -2.63906) (xy -3.31724 -2.74447) (xy -3.22961 -2.84734) (xy -3.13817 -2.94767)
				(xy -3.04419 -3.04419) (xy -2.94767 -3.13817) (xy -2.84734 -3.22961) (xy -2.74447 -3.31724) (xy -2.63906 -3.40233)
				(xy -2.53111 -3.48361) (xy -2.41935 -3.56108) (xy -2.30632 -3.63474) (xy -2.19202 -3.70586) (xy -2.07391 -3.77317)
				(xy -1.95453 -3.83667) (xy -1.83261 -3.89509) (xy -1.70942 -3.95097) (xy -1.58496 -4.00304) (xy -1.45796 -4.0513)
				(xy -1.33096 -4.09448) (xy -1.20142 -4.13385) (xy -1.07061 -4.17068) (xy -0.9398 -4.20116) (xy -0.80645 -4.2291)
				(xy -0.6731 -4.25196) (xy -0.53975 -4.27101) (xy -0.40513 -4.28625) (xy -0.27051 -4.29641) (xy -0.13462 -4.30276)
				(xy 0 -4.3053) (xy 0.13462 -4.30276) (xy 0.27051 -4.29641) (xy 0.40513 -4.28625) (xy 0.53975 -4.27101)
				(xy 0.6731 -4.25196) (xy 0.80645 -4.2291) (xy 0.9398 -4.20116) (xy 1.07061 -4.17068) (xy 1.20142 -4.13385)
				(xy 1.33096 -4.09448) (xy 1.45796 -4.0513) (xy 1.58496 -4.00304) (xy 1.70942 -3.95097) (xy 1.83261 -3.89509)
				(xy 1.95453 -3.83667) (xy 2.07391 -3.77317) (xy 2.19202 -3.70586) (xy 2.30632 -3.63474) (xy 2.41935 -3.56108)
				(xy 2.53111 -3.48361) (xy 2.63906 -3.40233) (xy 2.74447 -3.31724) (xy 2.84734 -3.22961) (xy 2.94767 -3.13817)
				(xy 3.04419 -3.04419) (xy 3.13817 -2.94767) (xy 3.22961 -2.84734) (xy 3.31724 -2.74447) (xy 3.40233 -2.63906)
				(xy 3.48361 -2.53111) (xy 3.56108 -2.41935) (xy 3.63474 -2.30632) (xy 3.70586 -2.19202) (xy 3.77317 -2.07391)
				(xy 3.83667 -1.95453) (xy 3.89509 -1.83261) (xy 3.95097 -1.70942) (xy 4.00304 -1.58496) (xy 4.0513 -1.45796)
				(xy 4.09448 -1.33096) (xy 4.13385 -1.20142) (xy 4.17068 -1.07061) (xy 4.20116 -0.9398) (xy 4.2291 -0.80645)
				(xy 4.25196 -0.6731) (xy 4.27101 -0.53975) (xy 4.28625 -0.40513) (xy 4.29641 -0.27051) (xy 4.30276 -0.13462)
				(xy 4.3053 0) (xy 4.30276 0.13462) (xy 4.29641 0.27051) (xy 4.28625 0.40513) (xy 4.27101 0.53975)
				(xy 4.25196 0.6731) (xy 4.2291 0.80645) (xy 4.20116 0.9398) (xy 4.17068 1.07061) (xy 4.13385 1.20142)
				(xy 4.09448 1.33096) (xy 4.0513 1.45796) (xy 4.00304 1.58496) (xy 3.95097 1.70942) (xy 3.89509 1.83261)
				(xy 3.83667 1.95453) (xy 3.77317 2.07391) (xy 3.70586 2.19202) (xy 3.63474 2.30632) (xy 3.56108 2.41935)
				(xy 3.48361 2.53111) (xy 3.40233 2.63906) (xy 3.31724 2.74447) (xy 3.22961 2.84734) (xy 3.13817 2.94767)
				(xy 3.04419 3.04419) (xy 2.94767 3.13817) (xy 2.84734 3.22961) (xy 2.74447 3.31724) (xy 2.63906 3.40233)
				(xy 2.53111 3.48361) (xy 2.41935 3.56108) (xy 2.30632 3.63474) (xy 2.19202 3.70586) (xy 2.07391 3.77317)
				(xy 1.95453 3.83667) (xy 1.83261 3.89509) (xy 1.70942 3.95097) (xy 1.58496 4.00304) (xy 1.45796 4.0513)
				(xy 1.33096 4.09448) (xy 1.20142 4.13385) (xy 1.07061 4.17068) (xy 0.9398 4.20116) (xy 0.80645 4.2291)
				(xy 0.6731 4.25196) (xy 0.53975 4.27101) (xy 0.40513 4.28625) (xy 0.27051 4.29641) (xy 0.13462 4.30276)
			)
			(stroke
				(width 0)
				(type default)
			)
			(fill no)
			(layer "F.Fab")
		)
		(pad "1" thru_hole circle
			(at 0 0)
			(size 8.001 8.001)
			(drill 3.5052)
			(layers "*.Cu" "*.Mask")
			(remove_unused_layers no)
			(net "GND")
			(clearance -1.7399)
			(thermal_gap 0.3048)
			(padstack
				(mode front_inner_back)
				(layer "Inner"
					(shape circle)
					(size 3.9116 3.9116)
					(clearance 0.3048)
				)
				(layer "B.Cu"
					(shape circle)
					(size 8.001 8.001)
					(clearance -1.7399)
				)
			)
		)
	)
	(footprint ""
		(layer "F.Cu")
		(at 4.040124 -17.29994 -90)
		(property "Reference" "CN6"
			(at 0 0 270)
			(layer "F.SilkS")
			(hide yes)
			(effects
				(font
					(size 1.27 1.27)
				)
			)
		)
		(property "Value" "JWT-CON5-42-GP"
			(at -7.8105 2.9591 270)
			(unlocked yes)
			(layer "F.Fab")
			(hide yes)
			(effects
				(font
					(size 1.016 1.016)
					(thickness 0.1524)
				)
			)
		)
		(property "Device Type" "A2541WR0-1TX5PA-6T-0E"
			(at -7.8105 1.4351 270)
			(unlocked yes)
			(layer "F.Fab")
			(hide yes)
			(effects
				(font
					(size 1.016 1.016)
					(thickness 0.1524)
				)
			)
		)
		(duplicate_pad_numbers_are_jumpers no)
		(fp_line
			(start -6.604 10.287)
			(end 6.604 10.287)
			(stroke
				(width 0.1524)
				(type default)
			)
			(layer "F.SilkS")
		)
		(fp_line
			(start 6.604 10.287)
			(end 6.604 -0.9652)
			(stroke
				(width 0.1524)
				(type default)
			)
			(layer "F.SilkS")
		)
		(fp_line
			(start -6.604 -0.9652)
			(end -6.604 10.287)
			(stroke
				(width 0.1524)
				(type default)
			)
			(layer "F.SilkS")
		)
		(fp_line
			(start 6.604 -0.9652)
			(end -6.604 -0.9652)
			(stroke
				(width 0.1524)
				(type default)
			)
			(layer "F.SilkS")
		)
		(fp_line
			(start -6.731 -1.0922)
			(end -6.731 0.1778)
			(stroke
				(width 0.4064)
				(type default)
			)
			(layer "F.SilkS")
		)
		(fp_line
			(start -5.461 -1.0922)
			(end -6.731 -1.0922)
			(stroke
				(width 0.4064)
				(type default)
			)
			(layer "F.SilkS")
		)
		(fp_circle
			(center -5.08 0)
			(end -5.08 -1.0668)
			(stroke
				(width 0.3048)
				(type default)
			)
			(fill no)
			(layer "F.SilkS")
		)
		(fp_circle
			(center -2.54 0)
			(end -2.54 -1.0668)
			(stroke
				(width 0.3048)
				(type default)
			)
			(fill no)
			(layer "F.SilkS")
		)
		(fp_circle
			(center 0 0)
			(end 0 -1.0668)
			(stroke
				(width 0.3048)
				(type default)
			)
			(fill no)
			(layer "F.SilkS")
		)
		(fp_circle
			(center 2.54 0)
			(end 2.54 -1.0668)
			(stroke
				(width 0.3048)
				(type default)
			)
			(fill no)
			(layer "F.SilkS")
		)
		(fp_circle
			(center 5.08 0)
			(end 5.08 -1.0668)
			(stroke
				(width 0.3048)
				(type default)
			)
			(fill no)
			(layer "F.SilkS")
		)
		(fp_rect
			(start -6.35 10.033)
			(end 6.35 -0.3302)
			(stroke
				(width 0)
				(type default)
			)
			(fill no)
			(layer "F.CrtYd")
		)
		(fp_poly
			(pts
				(xy -6.35 -0.3302) (xy 6.858 -0.3302) (xy 6.858 -1.2192) (xy -6.858 -1.2192) (xy -6.858 10.541)
				(xy 6.858 10.541) (xy 6.858 -0.3175) (xy 6.35 -0.3175) (xy 6.35 10.033) (xy -6.35 10.033)
			)
			(stroke
				(width 0)
				(type default)
			)
			(fill no)
			(layer "F.CrtYd")
		)
		(fp_rect
			(start -6.858 10.541)
			(end 6.858 -1.2192)
			(stroke
				(width 0)
				(type default)
			)
			(fill no)
			(layer "F.Fab")
		)
		(pad "1" thru_hole circle
			(at -5.08 0 270)
			(size 1.4224 1.4224)
			(drill 1.016)
			(layers "*.Cu" "*.Mask")
			(remove_unused_layers no)
			(net "GND")
			(clearance 0.1524)
			(thermal_gap 0.1524)
		)
		(pad "2" thru_hole circle
			(at -2.54 0 270)
			(size 1.4224 1.4224)
			(drill 1.016)
			(layers "*.Cu" "*.Mask")
			(remove_unused_layers no)
			(net "P12V_FAN6")
			(clearance 0.1524)
			(thermal_gap 0.1524)
		)
		(pad "3" thru_hole circle
			(at 0 0 270)
			(size 1.4224 1.4224)
			(drill 1.016)
			(layers "*.Cu" "*.Mask")
			(remove_unused_layers no)
			(net "FAN_TACH12")
			(clearance 0.1524)
			(thermal_gap 0.1524)
		)
		(pad "4" thru_hole circle
			(at 2.54 0 270)
			(size 1.4224 1.4224)
			(drill 1.016)
			(layers "*.Cu" "*.Mask")
			(remove_unused_layers no)
			(net "PWM_OUT_FAN6_NET")
			(clearance 0.1524)
			(thermal_gap 0.1524)
		)
		(pad "5" thru_hole circle
			(at 5.08 0 270)
			(size 1.4224 1.4224)
			(drill 1.016)
			(layers "*.Cu" "*.Mask")
			(remove_unused_layers no)
			(net "FAN_TACH11")
			(clearance 0.1524)
			(thermal_gap 0.1524)
		)
	)
	(footprint ""
		(layer "F.Cu")
		(at 20.585938 -15.595092 -90)
		(property "Reference" "R73"
			(at 0 0 270)
			(layer "F.SilkS")
			(hide yes)
			(effects
				(font
					(size 1.27 1.27)
				)
			)
		)
		(property "Value" "27KR3F-GP"
			(at -0.0254 -2.5146 270)
			(unlocked yes)
			(layer "F.Fab")
			(hide yes)
			(effects
				(font
					(size 1.016 1.016)
					(thickness 0.1524)
				)
			)
		)
		(property "Device Type" "R603H22"
			(at -0.0254 -4.0386 270)
			(unlocked yes)
			(layer "F.Fab")
			(hide yes)
			(effects
				(font
					(size 1.016 1.016)
					(thickness 0.1524)
				)
			)
		)
		(duplicate_pad_numbers_are_jumpers no)
		(fp_line
			(start -0.4826 0)
			(end -0.2032 0)
			(stroke
				(width 0.2032)
				(type default)
			)
			(layer "F.SilkS")
		)
		(fp_line
			(start 0.2032 0)
			(end 0.4826 0)
			(stroke
				(width 0.2032)
				(type default)
			)
			(layer "F.SilkS")
		)
		(fp_rect
			(start -0.5842 1.3335)
			(end 0.5842 -1.3335)
			(stroke
				(width 0)
				(type default)
			)
			(fill no)
			(layer "F.CrtYd")
		)
		(fp_rect
			(start -0.5842 1.3335)
			(end 0.5842 -1.3335)
			(stroke
				(width 0)
				(type default)
			)
			(fill no)
			(layer "F.Fab")
		)
		(pad "1" smd custom
			(at 0 -0.762 270)
			(size 0.2159 0.2159)
			(layers "F.Cu" "F.Mask" "F.Paste")
			(net "FANIN_11")
			(options
				(clearance outline)
				(anchor circle)
			)
			(primitives
				(gr_poly
					(pts
						(arc
							(start -0.3302 -0.4318)
							(mid -0.402042 -0.402042)
							(end -0.4318 -0.3302)
						)
						(arc
							(start -0.4318 0.3302)
							(mid -0.402042 0.402042)
							(end -0.3302 0.4318)
						)
						(arc
							(start 0.3302 0.4318)
							(mid 0.402042 0.402042)
							(end 0.4318 0.3302)
						)
						(arc
							(start 0.4318 -0.3302)
							(mid 0.402042 -0.402042)
							(end 0.3302 -0.4318)
						)
					)
					(width 0)
					(fill yes)
				)
			)
		)
		(pad "2" smd custom
			(at 0 0.762 270)
			(size 0.2159 0.2159)
			(layers "F.Cu" "F.Mask" "F.Paste")
			(net "FAN_TACH11")
			(options
				(clearance outline)
				(anchor circle)
			)
			(primitives
				(gr_poly
					(pts
						(arc
							(start -0.3302 -0.4318)
							(mid -0.402042 -0.402042)
							(end -0.4318 -0.3302)
						)
						(arc
							(start -0.4318 0.3302)
							(mid -0.402042 0.402042)
							(end -0.3302 0.4318)
						)
						(arc
							(start 0.3302 0.4318)
							(mid 0.402042 0.402042)
							(end 0.4318 0.3302)
						)
						(arc
							(start 0.4318 -0.3302)
							(mid 0.402042 -0.402042)
							(end 0.3302 -0.4318)
						)
					)
					(width 0)
					(fill yes)
				)
			)
		)
	)
)
